(kicad_pcb
	(version 20260206)
	(generator "pcbnew")
	(generator_version "10.0")
	(general
		(thickness 1.6)
		(legacy_teardrops no)
	)
	(paper "A4")
	(title_block
		(title "04192023_DAF0TMB3IC0_F0TG_MB_C_brd_V02_OCP.brd")
		(comment 1 "Grand Teton / footprints 8296-8304 of 8354")
	)
	(layers
		(0 "F.Cu" signal "TOP")
		(4 "In1.Cu" signal "GND")
		(6 "In2.Cu" signal "IN1")
		(8 "In3.Cu" signal "GND1")
		(10 "In4.Cu" signal "IN2")
		(12 "In5.Cu" signal "GND2")
		(14 "In6.Cu" signal "IN3")
		(16 "In7.Cu" signal "GND3")
		(18 "In8.Cu" signal "VCC")
		(20 "In9.Cu" signal "VCC1")
		(22 "In10.Cu" signal "GND4")
		(24 "In11.Cu" signal "IN4")
		(26 "In12.Cu" signal "GND5")
		(28 "In13.Cu" signal "IN5")
		(30 "In14.Cu" signal "GND6")
		(32 "In15.Cu" signal "IN6")
		(34 "In16.Cu" signal "GND7")
		(2 "B.Cu" signal "BOTTOM")
		(9 "F.Adhes" user "F.Adhesive")
		(11 "B.Adhes" user "B.Adhesive")
		(13 "F.Paste" user "Package Geometry/Pastemask Top")
		(15 "B.Paste" user "Package Geometry/Pastemask Bottom")
		(5 "F.SilkS" user "Ref Des/Silkscreen Top")
		(7 "B.SilkS" user "Ref Des/Silkscreen Bottom")
		(1 "F.Mask" user "Board Geometry/Soldermask Top")
		(3 "B.Mask" user "Board Geometry/Soldermask Bottom")
		(17 "Dwgs.User" user "User.Drawings")
		(19 "Cmts.User" user "User.Comments")
		(21 "Eco1.User" user "User.Eco1")
		(23 "Eco2.User" user "User.Eco2")
		(25 "Edge.Cuts" user "Board Geometry/Outline")
		(27 "Margin" user)
		(31 "F.CrtYd" user "Package Geometry/Place Bound Top")
		(29 "B.CrtYd" user "Package Geometry/Place Bound Bottom")
		(35 "F.Fab" user "Ref Des/Assembly Top")
		(33 "B.Fab" user "Ref Des/Assembly Bottom")
	)
	(footprint ""
		(layer "B.Cu")
		(at 234.844844 -329.173078 180)
		(property "Reference" "R1225"
			(at 0 0 0)
			(layer "B.SilkS")
			(hide yes)
			(effects
				(font
					(size 1.27 1.27)
				)
				(justify mirror)
			)
		)
		(property "Value" ""
			(at 0 0 0)
			(layer "B.Fab")
			(effects
				(font
					(size 1.27 1.27)
				)
				(justify mirror)
			)
		)
		(duplicate_pad_numbers_are_jumpers no)
		(fp_line
			(start 0.7874 0.4064)
			(end 0.7874 -0.4064)
			(stroke
				(width 0.1524)
				(type default)
			)
			(layer "B.SilkS")
		)
		(fp_line
			(start 0.7874 -0.4064)
			(end -0.7874 -0.4064)
			(stroke
				(width 0.1524)
				(type default)
			)
			(layer "B.SilkS")
		)
		(fp_line
			(start -0.7874 0.4064)
			(end 0.7874 0.4064)
			(stroke
				(width 0.1524)
				(type default)
			)
			(layer "B.SilkS")
		)
		(fp_line
			(start -0.7874 -0.4064)
			(end -0.7874 0.4064)
			(stroke
				(width 0.1524)
				(type default)
			)
			(layer "B.SilkS")
		)
		(fp_line
			(start 0.67945 0.3048)
			(end 0.67945 -0.305054)
			(stroke
				(width 0.1)
				(type default)
			)
			(layer "B.Fab")
		)
		(fp_line
			(start 0.67945 -0.305054)
			(end 0.12065 -0.305054)
			(stroke
				(width 0.1)
				(type default)
			)
			(layer "B.Fab")
		)
		(fp_line
			(start 0.12065 0.3048)
			(end 0.67945 0.3048)
			(stroke
				(width 0.1)
				(type default)
			)
			(layer "B.Fab")
		)
		(fp_line
			(start 0.12065 0.2794)
			(end 0.12065 0.3048)
			(stroke
				(width 0.1)
				(type default)
			)
			(layer "B.Fab")
		)
		(fp_line
			(start 0.12065 -0.2794)
			(end -0.12065 -0.2794)
			(stroke
				(width 0.1)
				(type default)
			)
			(layer "B.Fab")
		)
		(fp_line
			(start 0.12065 -0.305054)
			(end 0.12065 -0.2794)
			(stroke
				(width 0.1)
				(type default)
			)
			(layer "B.Fab")
		)
		(fp_line
			(start -0.120396 0.3048)
			(end -0.120396 0.2794)
			(stroke
				(width 0.1)
				(type default)
			)
			(layer "B.Fab")
		)
		(fp_line
			(start -0.120396 0.2794)
			(end 0.12065 0.2794)
			(stroke
				(width 0.1)
				(type default)
			)
			(layer "B.Fab")
		)
		(fp_line
			(start -0.12065 -0.2794)
			(end -0.12065 -0.3048)
			(stroke
				(width 0.1)
				(type default)
			)
			(layer "B.Fab")
		)
		(fp_line
			(start -0.12065 -0.3048)
			(end -0.67945 -0.3048)
			(stroke
				(width 0.1)
				(type default)
			)
			(layer "B.Fab")
		)
		(fp_line
			(start -0.67945 0.3048)
			(end -0.120396 0.3048)
			(stroke
				(width 0.1)
				(type default)
			)
			(layer "B.Fab")
		)
		(fp_line
			(start -0.67945 -0.3048)
			(end -0.67945 0.3048)
			(stroke
				(width 0.1)
				(type default)
			)
			(layer "B.Fab")
		)
		(pad "1" smd circle
			(at 0.40005 0)
			(size 0 0)
			(layers "B.Cu" "B.Mask" "B.Paste")
			(net "PVDD18_S5_P1_ADC")
		)
		(pad "2" smd circle
			(at -0.40005 0)
			(size 0 0)
			(layers "B.Cu" "B.Mask" "B.Paste")
			(net "GND")
		)
	)
	(footprint ""
		(layer "B.Cu")
		(at 61.918596 -388.011162 -90)
		(property "Reference" "C283"
			(at 0 0 90)
			(layer "B.SilkS")
			(hide yes)
			(effects
				(font
					(size 1.27 1.27)
				)
				(justify mirror)
			)
		)
		(property "Value" ""
			(at 0 0 90)
			(layer "B.Fab")
			(effects
				(font
					(size 1.27 1.27)
				)
				(justify mirror)
			)
		)
		(duplicate_pad_numbers_are_jumpers no)
		(fp_line
			(start -0.299974 0.150114)
			(end 0.299974 0.150114)
			(stroke
				(width 0.1)
				(type default)
			)
			(layer "B.Fab")
		)
		(fp_line
			(start 0.299974 0.150114)
			(end 0.299974 -0.150114)
			(stroke
				(width 0.1)
				(type default)
			)
			(layer "B.Fab")
		)
		(fp_line
			(start -0.299974 -0.150114)
			(end -0.299974 0.150114)
			(stroke
				(width 0.1)
				(type default)
			)
			(layer "B.Fab")
		)
		(fp_line
			(start 0.299974 -0.150114)
			(end -0.299974 -0.150114)
			(stroke
				(width 0.1)
				(type default)
			)
			(layer "B.Fab")
		)
		(pad "1" smd rect
			(at 0.2667 0 90)
			(size 0.3048 0.381)
			(layers "B.Cu" "B.Mask" "B.Paste")
			(net "P0V9_CPU1_RT0_2A")
		)
		(pad "2" smd rect
			(at -0.2667 0 90)
			(size 0.3048 0.381)
			(layers "B.Cu" "B.Mask" "B.Paste")
			(net "GND")
		)
	)
	(footprint ""
		(layer "B.Cu")
		(at 159.931608 -415.531046)
		(property "Reference" "C1068"
			(at 0 0 0)
			(layer "B.SilkS")
			(hide yes)
			(effects
				(font
					(size 1.27 1.27)
				)
				(justify mirror)
			)
		)
		(property "Value" ""
			(at 0 0 0)
			(layer "B.Fab")
			(effects
				(font
					(size 1.27 1.27)
				)
				(justify mirror)
			)
		)
		(duplicate_pad_numbers_are_jumpers no)
		(fp_line
			(start -0.299974 -0.150114)
			(end -0.299974 0.150114)
			(stroke
				(width 0.1)
				(type default)
			)
			(layer "B.Fab")
		)
		(fp_line
			(start -0.299974 0.150114)
			(end 0.299974 0.150114)
			(stroke
				(width 0.1)
				(type default)
			)
			(layer "B.Fab")
		)
		(fp_line
			(start 0.299974 -0.150114)
			(end -0.299974 -0.150114)
			(stroke
				(width 0.1)
				(type default)
			)
			(layer "B.Fab")
		)
		(fp_line
			(start 0.299974 0.150114)
			(end 0.299974 -0.150114)
			(stroke
				(width 0.1)
				(type default)
			)
			(layer "B.Fab")
		)
		(pad "1" smd rect
			(at 0.2667 0 180)
			(size 0.3048 0.381)
			(layers "B.Cu" "B.Mask" "B.Paste")
			(net "P3V3_AUX")
		)
		(pad "2" smd rect
			(at -0.2667 0 180)
			(size 0.3048 0.381)
			(layers "B.Cu" "B.Mask" "B.Paste")
			(net "GND")
		)
	)
	(footprint ""
		(layer "B.Cu")
		(at 372.6815 -261.935976)
		(property "Reference" "C2570"
			(at 0 0 0)
			(layer "B.SilkS")
			(hide yes)
			(effects
				(font
					(size 1.27 1.27)
				)
				(justify mirror)
			)
		)
		(property "Value" ""
			(at 0 0 0)
			(layer "B.Fab")
			(effects
				(font
					(size 1.27 1.27)
				)
				(justify mirror)
			)
		)
		(duplicate_pad_numbers_are_jumpers no)
		(fp_line
			(start -0.7874 -0.4064)
			(end -0.7874 0.4064)
			(stroke
				(width 0.1524)
				(type default)
			)
			(layer "B.SilkS")
		)
		(fp_line
			(start -0.7874 0.4064)
			(end 0.7874 0.4064)
			(stroke
				(width 0.1524)
				(type default)
			)
			(layer "B.SilkS")
		)
		(fp_line
			(start 0.7874 -0.4064)
			(end -0.7874 -0.4064)
			(stroke
				(width 0.1524)
				(type default)
			)
			(layer "B.SilkS")
		)
		(fp_line
			(start 0.7874 0.4064)
			(end 0.7874 -0.4064)
			(stroke
				(width 0.1524)
				(type default)
			)
			(layer "B.SilkS")
		)
		(fp_line
			(start -0.67945 -0.3048)
			(end -0.67945 0.3048)
			(stroke
				(width 0.1)
				(type default)
			)
			(layer "B.Fab")
		)
		(fp_line
			(start -0.67945 0.3048)
			(end -0.120396 0.3048)
			(stroke
				(width 0.1)
				(type default)
			)
			(layer "B.Fab")
		)
		(fp_line
			(start -0.12065 -0.3048)
			(end -0.67945 -0.3048)
			(stroke
				(width 0.1)
				(type default)
			)
			(layer "B.Fab")
		)
		(fp_line
			(start -0.12065 -0.2794)
			(end -0.12065 -0.3048)
			(stroke
				(width 0.1)
				(type default)
			)
			(layer "B.Fab")
		)
		(fp_line
			(start -0.120396 0.2794)
			(end 0.12065 0.2794)
			(stroke
				(width 0.1)
				(type default)
			)
			(layer "B.Fab")
		)
		(fp_line
			(start -0.120396 0.3048)
			(end -0.120396 0.2794)
			(stroke
				(width 0.1)
				(type default)
			)
			(layer "B.Fab")
		)
		(fp_line
			(start 0.12065 -0.305054)
			(end 0.12065 -0.2794)
			(stroke
				(width 0.1)
				(type default)
			)
			(layer "B.Fab")
		)
		(fp_line
			(start 0.12065 -0.2794)
			(end -0.12065 -0.2794)
			(stroke
				(width 0.1)
				(type default)
			)
			(layer "B.Fab")
		)
		(fp_line
			(start 0.12065 0.2794)
			(end 0.12065 0.3048)
			(stroke
				(width 0.1)
				(type default)
			)
			(layer "B.Fab")
		)
		(fp_line
			(start 0.12065 0.3048)
			(end 0.67945 0.3048)
			(stroke
				(width 0.1)
				(type default)
			)
			(layer "B.Fab")
		)
		(fp_line
			(start 0.67945 -0.305054)
			(end 0.12065 -0.305054)
			(stroke
				(width 0.1)
				(type default)
			)
			(layer "B.Fab")
		)
		(fp_line
			(start 0.67945 0.3048)
			(end 0.67945 -0.305054)
			(stroke
				(width 0.1)
				(type default)
			)
			(layer "B.Fab")
		)
		(pad "1" smd circle
			(at 0.40005 0 180)
			(size 0 0)
			(layers "B.Cu" "B.Mask" "B.Paste")
			(net "PVDDCR_SOC_P0")
		)
		(pad "2" smd circle
			(at -0.40005 0 180)
			(size 0 0)
			(layers "B.Cu" "B.Mask" "B.Paste")
			(net "GND")
		)
	)
	(footprint ""
		(layer "B.Cu")
		(at 229.87 -232.156 90)
		(property "Reference" "R5004"
			(at 0 0 90)
			(layer "B.SilkS")
			(hide yes)
			(effects
				(font
					(size 1.27 1.27)
				)
				(justify mirror)
			)
		)
		(property "Value" ""
			(at 0 0 90)
			(layer "B.Fab")
			(effects
				(font
					(size 1.27 1.27)
				)
				(justify mirror)
			)
		)
		(duplicate_pad_numbers_are_jumpers no)
		(fp_line
			(start 0.7874 -0.4064)
			(end -0.7874 -0.4064)
			(stroke
				(width 0.1524)
				(type default)
			)
			(layer "B.SilkS")
		)
		(fp_line
			(start -0.7874 -0.4064)
			(end -0.7874 0.4064)
			(stroke
				(width 0.1524)
				(type default)
			)
			(layer "B.SilkS")
		)
		(fp_line
			(start 0.7874 0.4064)
			(end 0.7874 -0.4064)
			(stroke
				(width 0.1524)
				(type default)
			)
			(layer "B.SilkS")
		)
		(fp_line
			(start -0.7874 0.4064)
			(end 0.7874 0.4064)
			(stroke
				(width 0.1524)
				(type default)
			)
			(layer "B.SilkS")
		)
		(fp_line
			(start 0.67945 -0.305054)
			(end 0.12065 -0.305054)
			(stroke
				(width 0.1)
				(type default)
			)
			(layer "B.Fab")
		)
		(fp_line
			(start 0.12065 -0.305054)
			(end 0.12065 -0.2794)
			(stroke
				(width 0.1)
				(type default)
			)
			(layer "B.Fab")
		)
		(fp_line
			(start -0.12065 -0.3048)
			(end -0.67945 -0.3048)
			(stroke
				(width 0.1)
				(type default)
			)
			(layer "B.Fab")
		)
		(fp_line
			(start -0.67945 -0.3048)
			(end -0.67945 0.3048)
			(stroke
				(width 0.1)
				(type default)
			)
			(layer "B.Fab")
		)
		(fp_line
			(start 0.12065 -0.2794)
			(end -0.12065 -0.2794)
			(stroke
				(width 0.1)
				(type default)
			)
			(layer "B.Fab")
		)
		(fp_line
			(start -0.12065 -0.2794)
			(end -0.12065 -0.3048)
			(stroke
				(width 0.1)
				(type default)
			)
			(layer "B.Fab")
		)
		(fp_line
			(start 0.12065 0.2794)
			(end 0.12065 0.3048)
			(stroke
				(width 0.1)
				(type default)
			)
			(layer "B.Fab")
		)
		(fp_line
			(start -0.120396 0.2794)
			(end 0.12065 0.2794)
			(stroke
				(width 0.1)
				(type default)
			)
			(layer "B.Fab")
		)
		(fp_line
			(start 0.67945 0.3048)
			(end 0.67945 -0.305054)
			(stroke
				(width 0.1)
				(type default)
			)
			(layer "B.Fab")
		)
		(fp_line
			(start 0.12065 0.3048)
			(end 0.67945 0.3048)
			(stroke
				(width 0.1)
				(type default)
			)
			(layer "B.Fab")
		)
		(fp_line
			(start -0.120396 0.3048)
			(end -0.120396 0.2794)
			(stroke
				(width 0.1)
				(type default)
			)
			(layer "B.Fab")
		)
		(fp_line
			(start -0.67945 0.3048)
			(end -0.120396 0.3048)
			(stroke
				(width 0.1)
				(type default)
			)
			(layer "B.Fab")
		)
		(pad "1" smd circle
			(at 0.40005 0 270)
			(size 0 0)
			(layers "B.Cu" "B.Mask" "B.Paste")
			(net "SMB_APML_CPU1_R_SDA")
		)
		(pad "2" smd circle
			(at -0.40005 0 270)
			(size 0 0)
			(layers "B.Cu" "B.Mask" "B.Paste")
			(net "GND")
		)
	)
	(footprint ""
		(layer "B.Cu")
		(at 217.17 -331.724 180)
		(property "Reference" "R6771"
			(at 0 0 0)
			(layer "B.SilkS")
			(hide yes)
			(effects
				(font
					(size 1.27 1.27)
				)
				(justify mirror)
			)
		)
		(property "Value" ""
			(at 0 0 0)
			(layer "B.Fab")
			(effects
				(font
					(size 1.27 1.27)
				)
				(justify mirror)
			)
		)
		(duplicate_pad_numbers_are_jumpers no)
		(fp_line
			(start 0.32512 0.175006)
			(end 0.32512 -0.175006)
			(stroke
				(width 0.1)
				(type default)
			)
			(layer "B.Fab")
		)
		(fp_line
			(start 0.32512 -0.175006)
			(end -0.32512 -0.175006)
			(stroke
				(width 0.1)
				(type default)
			)
			(layer "B.Fab")
		)
		(fp_line
			(start -0.32512 0.175006)
			(end 0.32512 0.175006)
			(stroke
				(width 0.1)
				(type default)
			)
			(layer "B.Fab")
		)
		(fp_line
			(start -0.32512 -0.175006)
			(end -0.32512 0.175006)
			(stroke
				(width 0.1)
				(type default)
			)
			(layer "B.Fab")
		)
		(pad "1" smd rect
			(at 0.2667 0)
			(size 0.3048 0.381)
			(layers "B.Cu" "B.Mask" "B.Paste")
			(net "P1V8_AUX")
		)
		(pad "2" smd rect
			(at -0.2667 0 180)
			(size 0.3048 0.381)
			(layers "B.Cu" "B.Mask" "B.Paste")
			(net "RT_SMB_MUX_ADDR1")
		)
	)
	(footprint ""
		(layer "B.Cu")
		(at 241.140488 -330.581 180)
		(property "Reference" "R844"
			(at 0 0 0)
			(layer "B.SilkS")
			(hide yes)
			(effects
				(font
					(size 1.27 1.27)
				)
				(justify mirror)
			)
		)
		(property "Value" ""
			(at 0 0 0)
			(layer "B.Fab")
			(effects
				(font
					(size 1.27 1.27)
				)
				(justify mirror)
			)
		)
		(duplicate_pad_numbers_are_jumpers no)
		(fp_line
			(start 0.32512 0.175006)
			(end 0.32512 -0.175006)
			(stroke
				(width 0.1)
				(type default)
			)
			(layer "B.Fab")
		)
		(fp_line
			(start 0.32512 -0.175006)
			(end -0.32512 -0.175006)
			(stroke
				(width 0.1)
				(type default)
			)
			(layer "B.Fab")
		)
		(fp_line
			(start -0.32512 0.175006)
			(end 0.32512 0.175006)
			(stroke
				(width 0.1)
				(type default)
			)
			(layer "B.Fab")
		)
		(fp_line
			(start -0.32512 -0.175006)
			(end -0.32512 0.175006)
			(stroke
				(width 0.1)
				(type default)
			)
			(layer "B.Fab")
		)
		(pad "1" smd rect
			(at 0.2667 0)
			(size 0.3048 0.381)
			(layers "B.Cu" "B.Mask" "B.Paste")
			(net "P1V8_AUX")
		)
		(pad "2" smd rect
			(at -0.2667 0 180)
			(size 0.3048 0.381)
			(layers "B.Cu" "B.Mask" "B.Paste")
			(net "RT_ROM_SMB_MUX_ADDR0")
		)
	)
	(footprint ""
		(layer "B.Cu")
		(at 352.706178 -395.148562 90)
		(property "Reference" "C643"
			(at 0 0 90)
			(layer "B.SilkS")
			(hide yes)
			(effects
				(font
					(size 1.27 1.27)
				)
				(justify mirror)
			)
		)
		(property "Value" ""
			(at 0 0 90)
			(layer "B.Fab")
			(effects
				(font
					(size 1.27 1.27)
				)
				(justify mirror)
			)
		)
		(duplicate_pad_numbers_are_jumpers no)
		(fp_line
			(start 0.299974 -0.150114)
			(end -0.299974 -0.150114)
			(stroke
				(width 0.1)
				(type default)
			)
			(layer "B.Fab")
		)
		(fp_line
			(start -0.299974 -0.150114)
			(end -0.299974 0.150114)
			(stroke
				(width 0.1)
				(type default)
			)
			(layer "B.Fab")
		)
		(fp_line
			(start 0.299974 0.150114)
			(end 0.299974 -0.150114)
			(stroke
				(width 0.1)
				(type default)
			)
			(layer "B.Fab")
		)
		(fp_line
			(start -0.299974 0.150114)
			(end 0.299974 0.150114)
			(stroke
				(width 0.1)
				(type default)
			)
			(layer "B.Fab")
		)
		(pad "1" smd rect
			(at 0.2667 0 270)
			(size 0.3048 0.381)
			(layers "B.Cu" "B.Mask" "B.Paste")
			(net "P0V9_CPU0_RT1_2A")
		)
		(pad "2" smd rect
			(at -0.2667 0 270)
			(size 0.3048 0.381)
			(layers "B.Cu" "B.Mask" "B.Paste")
			(net "GND")
		)
	)
	(footprint ""
		(layer "B.Cu")
		(at 385.567682 -416.899344 90)
		(property "Reference" "C6605"
			(at 0 0 90)
			(layer "B.SilkS")
			(hide yes)
			(effects
				(font
					(size 1.27 1.27)
				)
				(justify mirror)
			)
		)
		(property "Value" ""
			(at 0 0 90)
			(layer "B.Fab")
			(effects
				(font
					(size 1.27 1.27)
				)
				(justify mirror)
			)
		)
		(duplicate_pad_numbers_are_jumpers no)
		(fp_line
			(start 0.299974 -0.150114)
			(end -0.299974 -0.150114)
			(stroke
				(width 0.1)
				(type default)
			)
			(layer "B.Fab")
		)
		(fp_line
			(start -0.299974 -0.150114)
			(end -0.299974 0.150114)
			(stroke
				(width 0.1)
				(type default)
			)
			(layer "B.Fab")
		)
		(fp_line
			(start 0.299974 0.150114)
			(end 0.299974 -0.150114)
			(stroke
				(width 0.1)
				(type default)
			)
			(layer "B.Fab")
		)
		(fp_line
			(start -0.299974 0.150114)
			(end 0.299974 0.150114)
			(stroke
				(width 0.1)
				(type default)
			)
			(layer "B.Fab")
		)
		(pad "1" smd rect
			(at 0.2667 0 270)
			(size 0.3048 0.381)
			(layers "B.Cu" "B.Mask" "B.Paste")
			(net "P5E_CPU0_P3_TX_BUF_C_DP<4>")
		)
		(pad "2" smd rect
			(at -0.2667 0 270)
			(size 0.3048 0.381)
			(layers "B.Cu" "B.Mask" "B.Paste")
			(net "P5E_CPU0_P3_TX_BUF_DP<4>")
		)
	)
)
